FILE_TYPE=LIBRARY_PARTS;
primitive 'NC7SB3157';
  pin
    'S':
      PIN_NUMBER='(6)';
      PIN_TYPE='ANALOG';
      NO_LOAD_CHECK='BOTH';
      NO_IO_CHECK='BOTH';
      ALLOW_CONNECT='TRUE';
    'B0':
      PIN_NUMBER='(3)';
      PIN_TYPE='ANALOG';
      NO_LOAD_CHECK='BOTH';
      NO_IO_CHECK='BOTH';
      ALLOW_CONNECT='TRUE';
    'B1':
      PIN_NUMBER='(1)';
      PIN_TYPE='ANALOG';
      NO_LOAD_CHECK='BOTH';
      NO_IO_CHECK='BOTH';
      ALLOW_CONNECT='TRUE';
    'A':
      PIN_NUMBER='(4)';
      PIN_TYPE='ANALOG';
      NO_LOAD_CHECK='BOTH';
      NO_IO_CHECK='BOTH';
      ALLOW_CONNECT='TRUE';
    'VCC':
      PIN_NUMBER='(5)';
      PIN_TYPE='ANALOG';
      NO_LOAD_CHECK='BOTH';
      NO_IO_CHECK='BOTH';
      ALLOW_CONNECT='TRUE';
    'GND':
      PIN_NUMBER='(2)';
      PIN_TYPE='ANALOG';
      NO_LOAD_CHECK='BOTH';
      NO_IO_CHECK='BOTH';
      ALLOW_CONNECT='TRUE';
  end_pin;
  body
    PART_NAME='NC7SB3157';
    CLASS='IC';
    PHYS_DES_PREFIX='U';
  end_body;
end_primitive;
END.

